(kicad_pcb
	(version 20260206)
	(generator "pcbnew")
	(generator_version "10.0")
	(general
		(thickness 1.6)
		(legacy_teardrops no)
	)
	(paper "A4")
	(title_block
		(title "Wiwynn_Tioga_Pass_MB.brd")
		(comment 1 "Tioga Pass / footprint 2838 of 4770 (J6U2), pads 1-123 of 291")
	)
	(layers
		(0 "F.Cu" signal "TOP")
		(4 "In1.Cu" signal "L2GND")
		(6 "In2.Cu" signal "L3")
		(8 "In3.Cu" signal "L4GND")
		(10 "In4.Cu" signal "L5")
		(12 "In5.Cu" signal "L6GND")
		(14 "In6.Cu" signal "L7VCC")
		(16 "In7.Cu" signal "L8VCC")
		(18 "In8.Cu" signal "L9GND")
		(20 "In9.Cu" signal "L10")
		(22 "In10.Cu" signal "L11GND")
		(24 "In11.Cu" signal "L12")
		(26 "In12.Cu" signal "L13GND")
		(2 "B.Cu" signal "BOTTOM")
		(9 "F.Adhes" user "F.Adhesive")
		(11 "B.Adhes" user "B.Adhesive")
		(13 "F.Paste" user "Package Geometry/Pastemask Top")
		(15 "B.Paste" user "Package Geometry/Pastemask Bottom")
		(5 "F.SilkS" user "Ref Des/Silkscreen Top")
		(7 "B.SilkS" user "Ref Des/Silkscreen Bottom")
		(1 "F.Mask" user "Board Geometry/Soldermask Top")
		(3 "B.Mask" user "Board Geometry/Soldermask Bottom")
		(17 "Dwgs.User" user "User.Drawings")
		(19 "Cmts.User" user "User.Comments")
		(21 "Eco1.User" user "User.Eco1")
		(23 "Eco2.User" user "User.Eco2")
		(25 "Edge.Cuts" user "Board Geometry/Outline")
		(27 "Margin" user)
		(31 "F.CrtYd" user "Package Geometry/Place Bound Top")
		(29 "B.CrtYd" user "Package Geometry/Place Bound Bottom")
		(35 "F.Fab" user "Ref Des/Assembly Top")
		(33 "B.Fab" user "Ref Des/Assembly Bottom")
	)
	(footprint ""
		(layer "B.Cu")
		(at 194.700398 -5.621782 90)
		(property "Reference" "J6U2"
			(at 2.225548 39.48811 0)
			(unlocked yes)
			(layer "B.SilkS")
			(effects
				(font
					(size 0.7874 0.5842)
					(thickness 0.1524)
				)
				(justify left mirror)
			)
		)
		(property "Value" ""
			(at 0 0 90)
			(layer "B.Fab")
			(effects
				(font
					(size 1.27 1.27)
				)
				(justify mirror)
			)
		)
		(duplicate_pad_numbers_are_jumpers no)
		(pad "" thru_hole circle
			(at -2.29997 -5.649976 270)
			(size 2.8194 2.8194)
			(drill 2.4384)
			(layers "*.Cu" "*.Mask")
			(remove_unused_layers no)
			(clearance 0.127)
			(thermal_gap 0.127)
		)
		(pad "" thru_hole oval
			(at -2.29997 68.90004 270)
			(size 2.8194 1.5748)
			(drill oval 2.4384 1.1938)
			(layers "*.Cu" "*.Mask")
			(remove_unused_layers no)
			(clearance 0.127)
			(thermal_gap 0.127)
		)
		(pad "" thru_hole circle
			(at -2.29997 132.299964 270)
			(size 2.8194 2.8194)
			(drill 2.4384)
			(layers "*.Cu" "*.Mask")
			(remove_unused_layers no)
			(clearance 0.127)
			(thermal_gap 0.127)
		)
		(pad "1" smd rect
			(at 0 0 270)
			(size 1.8034 0.508)
			(layers "B.Cu" "B.Mask" "B.Paste")
			(net "P12V_NVDIMM_ABC")
		)
		(pad "2" smd rect
			(at 0 0.849884 270)
			(size 1.8034 0.508)
			(layers "B.Cu" "B.Mask" "B.Paste")
			(net "GND")
		)
		(pad "3" smd rect
			(at 0 1.700022 270)
			(size 1.8034 0.508)
			(layers "B.Cu" "B.Mask" "B.Paste")
			(net "M_C_DQ<4>")
		)
		(pad "4" smd rect
			(at 0 2.549906 270)
			(size 1.8034 0.508)
			(layers "B.Cu" "B.Mask" "B.Paste")
			(net "GND")
		)
		(pad "5" smd rect
			(at 0 3.400044 270)
			(size 1.8034 0.508)
			(layers "B.Cu" "B.Mask" "B.Paste")
			(net "M_C_DQ<0>")
		)
		(pad "6" smd rect
			(at 0 4.249928 270)
			(size 1.8034 0.508)
			(layers "B.Cu" "B.Mask" "B.Paste")
			(net "GND")
		)
		(pad "7" smd rect
			(at 0 5.100066 270)
			(size 1.8034 0.508)
			(layers "B.Cu" "B.Mask" "B.Paste")
			(net "M_C_DQS_DP<9>")
		)
		(pad "8" smd rect
			(at 0 5.94995 270)
			(size 1.8034 0.508)
			(layers "B.Cu" "B.Mask" "B.Paste")
			(net "M_C_DQS_DN<9>")
		)
		(pad "9" smd rect
			(at 0 6.800088 270)
			(size 1.8034 0.508)
			(layers "B.Cu" "B.Mask" "B.Paste")
			(net "GND")
		)
		(pad "10" smd rect
			(at 0 7.649972 270)
			(size 1.8034 0.508)
			(layers "B.Cu" "B.Mask" "B.Paste")
			(net "M_C_DQ<6>")
		)
		(pad "11" smd rect
			(at 0 8.50011 270)
			(size 1.8034 0.508)
			(layers "B.Cu" "B.Mask" "B.Paste")
			(net "GND")
		)
		(pad "12" smd rect
			(at 0 9.349994 270)
			(size 1.8034 0.508)
			(layers "B.Cu" "B.Mask" "B.Paste")
			(net "M_C_DQ<2>")
		)
		(pad "13" smd rect
			(at 0 10.199878 270)
			(size 1.8034 0.508)
			(layers "B.Cu" "B.Mask" "B.Paste")
			(net "GND")
		)
		(pad "14" smd rect
			(at 0 11.050016 270)
			(size 1.8034 0.508)
			(layers "B.Cu" "B.Mask" "B.Paste")
			(net "M_C_DQ<12>")
		)
		(pad "15" smd rect
			(at 0 11.8999 270)
			(size 1.8034 0.508)
			(layers "B.Cu" "B.Mask" "B.Paste")
			(net "GND")
		)
		(pad "16" smd rect
			(at 0 12.750038 270)
			(size 1.8034 0.508)
			(layers "B.Cu" "B.Mask" "B.Paste")
			(net "M_C_DQ<8>")
		)
		(pad "17" smd rect
			(at 0 13.599922 270)
			(size 1.8034 0.508)
			(layers "B.Cu" "B.Mask" "B.Paste")
			(net "GND")
		)
		(pad "18" smd rect
			(at 0 14.45006 270)
			(size 1.8034 0.508)
			(layers "B.Cu" "B.Mask" "B.Paste")
			(net "M_C_DQS_DP<10>")
		)
		(pad "19" smd rect
			(at 0 15.299944 270)
			(size 1.8034 0.508)
			(layers "B.Cu" "B.Mask" "B.Paste")
			(net "M_C_DQS_DN<10>")
		)
		(pad "20" smd rect
			(at 0 16.150082 270)
			(size 1.8034 0.508)
			(layers "B.Cu" "B.Mask" "B.Paste")
			(net "GND")
		)
		(pad "21" smd rect
			(at 0 16.999966 270)
			(size 1.8034 0.508)
			(layers "B.Cu" "B.Mask" "B.Paste")
			(net "M_C_DQ<14>")
		)
		(pad "22" smd rect
			(at 0 17.850104 270)
			(size 1.8034 0.508)
			(layers "B.Cu" "B.Mask" "B.Paste")
			(net "GND")
		)
		(pad "23" smd rect
			(at 0 18.699988 270)
			(size 1.8034 0.508)
			(layers "B.Cu" "B.Mask" "B.Paste")
			(net "M_C_DQ<10>")
		)
		(pad "24" smd rect
			(at 0 19.550126 270)
			(size 1.8034 0.508)
			(layers "B.Cu" "B.Mask" "B.Paste")
			(net "GND")
		)
		(pad "25" smd rect
			(at 0 20.40001 270)
			(size 1.8034 0.508)
			(layers "B.Cu" "B.Mask" "B.Paste")
			(net "M_C_DQ<20>")
		)
		(pad "26" smd rect
			(at 0 21.249894 270)
			(size 1.8034 0.508)
			(layers "B.Cu" "B.Mask" "B.Paste")
			(net "GND")
		)
		(pad "27" smd rect
			(at 0 22.100032 270)
			(size 1.8034 0.508)
			(layers "B.Cu" "B.Mask" "B.Paste")
			(net "M_C_DQ<16>")
		)
		(pad "28" smd rect
			(at 0 22.949916 270)
			(size 1.8034 0.508)
			(layers "B.Cu" "B.Mask" "B.Paste")
			(net "GND")
		)
		(pad "29" smd rect
			(at 0 23.800054 270)
			(size 1.8034 0.508)
			(layers "B.Cu" "B.Mask" "B.Paste")
			(net "M_C_DQS_DP<11>")
		)
		(pad "30" smd rect
			(at 0 24.649938 270)
			(size 1.8034 0.508)
			(layers "B.Cu" "B.Mask" "B.Paste")
			(net "M_C_DQS_DN<11>")
		)
		(pad "31" smd rect
			(at 0 25.500076 270)
			(size 1.8034 0.508)
			(layers "B.Cu" "B.Mask" "B.Paste")
			(net "GND")
		)
		(pad "32" smd rect
			(at 0 26.34996 270)
			(size 1.8034 0.508)
			(layers "B.Cu" "B.Mask" "B.Paste")
			(net "M_C_DQ<22>")
		)
		(pad "33" smd rect
			(at 0 27.200098 270)
			(size 1.8034 0.508)
			(layers "B.Cu" "B.Mask" "B.Paste")
			(net "GND")
		)
		(pad "34" smd rect
			(at 0 28.049982 270)
			(size 1.8034 0.508)
			(layers "B.Cu" "B.Mask" "B.Paste")
			(net "M_C_DQ<18>")
		)
		(pad "35" smd rect
			(at 0 28.90012 270)
			(size 1.8034 0.508)
			(layers "B.Cu" "B.Mask" "B.Paste")
			(net "GND")
		)
		(pad "36" smd rect
			(at 0 29.750004 270)
			(size 1.8034 0.508)
			(layers "B.Cu" "B.Mask" "B.Paste")
			(net "M_C_DQ<28>")
		)
		(pad "37" smd rect
			(at 0 30.599888 270)
			(size 1.8034 0.508)
			(layers "B.Cu" "B.Mask" "B.Paste")
			(net "GND")
		)
		(pad "38" smd rect
			(at 0 31.450026 270)
			(size 1.8034 0.508)
			(layers "B.Cu" "B.Mask" "B.Paste")
			(net "M_C_DQ<24>")
		)
		(pad "39" smd rect
			(at 0 32.29991 270)
			(size 1.8034 0.508)
			(layers "B.Cu" "B.Mask" "B.Paste")
			(net "GND")
		)
		(pad "40" smd rect
			(at 0 33.150048 270)
			(size 1.8034 0.508)
			(layers "B.Cu" "B.Mask" "B.Paste")
			(net "M_C_DQS_DP<12>")
		)
		(pad "41" smd rect
			(at 0 33.999932 270)
			(size 1.8034 0.508)
			(layers "B.Cu" "B.Mask" "B.Paste")
			(net "M_C_DQS_DN<12>")
		)
		(pad "42" smd rect
			(at 0 34.85007 270)
			(size 1.8034 0.508)
			(layers "B.Cu" "B.Mask" "B.Paste")
			(net "GND")
		)
		(pad "43" smd rect
			(at 0 35.699954 270)
			(size 1.8034 0.508)
			(layers "B.Cu" "B.Mask" "B.Paste")
			(net "M_C_DQ<30>")
		)
		(pad "44" smd rect
			(at 0 36.550092 270)
			(size 1.8034 0.508)
			(layers "B.Cu" "B.Mask" "B.Paste")
			(net "GND")
		)
		(pad "45" smd rect
			(at 0 37.399976 270)
			(size 1.8034 0.508)
			(layers "B.Cu" "B.Mask" "B.Paste")
			(net "M_C_DQ<26>")
		)
		(pad "46" smd rect
			(at 0 38.250114 270)
			(size 1.8034 0.508)
			(layers "B.Cu" "B.Mask" "B.Paste")
			(net "GND")
		)
		(pad "47" smd rect
			(at 0 39.099998 270)
			(size 1.8034 0.508)
			(layers "B.Cu" "B.Mask" "B.Paste")
			(net "M_C_ECC<4>")
		)
		(pad "48" smd rect
			(at 0 39.949882 270)
			(size 1.8034 0.508)
			(layers "B.Cu" "B.Mask" "B.Paste")
			(net "GND")
		)
		(pad "49" smd rect
			(at 0 40.80002 270)
			(size 1.8034 0.508)
			(layers "B.Cu" "B.Mask" "B.Paste")
			(net "M_C_ECC<0>")
		)
		(pad "50" smd rect
			(at 0 41.649904 270)
			(size 1.8034 0.508)
			(layers "B.Cu" "B.Mask" "B.Paste")
			(net "GND")
		)
		(pad "51" smd rect
			(at 0 42.500042 270)
			(size 1.8034 0.508)
			(layers "B.Cu" "B.Mask" "B.Paste")
			(net "M_C_DQS_DP<17>")
		)
		(pad "52" smd rect
			(at 0 43.349926 270)
			(size 1.8034 0.508)
			(layers "B.Cu" "B.Mask" "B.Paste")
			(net "M_C_DQS_DN<17>")
		)
		(pad "53" smd rect
			(at 0 44.200064 270)
			(size 1.8034 0.508)
			(layers "B.Cu" "B.Mask" "B.Paste")
			(net "GND")
		)
		(pad "54" smd rect
			(at 0 45.049948 270)
			(size 1.8034 0.508)
			(layers "B.Cu" "B.Mask" "B.Paste")
			(net "M_C_ECC<6>")
		)
		(pad "55" smd rect
			(at 0 45.900086 270)
			(size 1.8034 0.508)
			(layers "B.Cu" "B.Mask" "B.Paste")
			(net "GND")
		)
		(pad "56" smd rect
			(at 0 46.74997 270)
			(size 1.8034 0.508)
			(layers "B.Cu" "B.Mask" "B.Paste")
			(net "M_C_ECC<2>")
		)
		(pad "57" smd rect
			(at 0 47.600108 270)
			(size 1.8034 0.508)
			(layers "B.Cu" "B.Mask" "B.Paste")
			(net "GND")
		)
		(pad "58" smd rect
			(at 0 48.449992 270)
			(size 1.8034 0.508)
			(layers "B.Cu" "B.Mask" "B.Paste")
			(net "M_ABC_RST_N")
		)
		(pad "59" smd rect
			(at 0 49.299876 270)
			(size 1.8034 0.508)
			(layers "B.Cu" "B.Mask" "B.Paste")
			(net "PVDDQ_ABC")
		)
		(pad "60" smd rect
			(at 0 50.150014 270)
			(size 1.8034 0.508)
			(layers "B.Cu" "B.Mask" "B.Paste")
			(net "M_C_CKE<2>")
		)
		(pad "61" smd rect
			(at 0 50.999898 270)
			(size 1.8034 0.508)
			(layers "B.Cu" "B.Mask" "B.Paste")
			(net "PVDDQ_ABC")
		)
		(pad "62" smd rect
			(at 0 51.850036 270)
			(size 1.8034 0.508)
			(layers "B.Cu" "B.Mask" "B.Paste")
			(net "M_C_ACT_N")
		)
		(pad "63" smd rect
			(at 0 52.69992 270)
			(size 1.8034 0.508)
			(layers "B.Cu" "B.Mask" "B.Paste")
			(net "M_C_BG<0>")
		)
		(pad "64" smd rect
			(at 0 53.550058 270)
			(size 1.8034 0.508)
			(layers "B.Cu" "B.Mask" "B.Paste")
			(net "PVDDQ_ABC")
		)
		(pad "65" smd rect
			(at 0 54.399942 270)
			(size 1.8034 0.508)
			(layers "B.Cu" "B.Mask" "B.Paste")
			(net "M_C_MA<12>")
		)
		(pad "66" smd rect
			(at 0 55.25008 270)
			(size 1.8034 0.508)
			(layers "B.Cu" "B.Mask" "B.Paste")
			(net "M_C_MA<9>")
		)
		(pad "67" smd rect
			(at 0 56.099964 270)
			(size 1.8034 0.508)
			(layers "B.Cu" "B.Mask" "B.Paste")
			(net "PVDDQ_ABC")
		)
		(pad "68" smd rect
			(at 0 56.950102 270)
			(size 1.8034 0.508)
			(layers "B.Cu" "B.Mask" "B.Paste")
			(net "M_C_MA<8>")
		)
		(pad "69" smd rect
			(at 0 57.799986 270)
			(size 1.8034 0.508)
			(layers "B.Cu" "B.Mask" "B.Paste")
			(net "M_C_MA<6>")
		)
		(pad "70" smd rect
			(at 0 58.650124 270)
			(size 1.8034 0.508)
			(layers "B.Cu" "B.Mask" "B.Paste")
			(net "PVDDQ_ABC")
		)
		(pad "71" smd rect
			(at 0 59.500008 270)
			(size 1.8034 0.508)
			(layers "B.Cu" "B.Mask" "B.Paste")
			(net "M_C_MA<3>")
		)
		(pad "72" smd rect
			(at 0 60.349892 270)
			(size 1.8034 0.508)
			(layers "B.Cu" "B.Mask" "B.Paste")
			(net "M_C_MA<1>")
		)
		(pad "73" smd rect
			(at 0 61.20003 270)
			(size 1.8034 0.508)
			(layers "B.Cu" "B.Mask" "B.Paste")
			(net "PVDDQ_ABC")
		)
		(pad "74" smd rect
			(at 0 62.049914 270)
			(size 1.8034 0.508)
			(layers "B.Cu" "B.Mask" "B.Paste")
			(net "M_C_CLK_DP<2>")
		)
		(pad "75" smd rect
			(at 0 62.900052 270)
			(size 1.8034 0.508)
			(layers "B.Cu" "B.Mask" "B.Paste")
			(net "M_C_CLK_DN<2>")
		)
		(pad "76" smd rect
			(at 0 63.749936 270)
			(size 1.8034 0.508)
			(layers "B.Cu" "B.Mask" "B.Paste")
			(net "PVDDQ_ABC")
		)
		(pad "77" smd rect
			(at 0 64.600074 270)
			(size 1.8034 0.508)
			(layers "B.Cu" "B.Mask" "B.Paste")
			(net "PVTT_ABC")
		)
		(pad "78" smd rect
			(at 0 70.550024 270)
			(size 1.8034 0.508)
			(layers "B.Cu" "B.Mask" "B.Paste")
			(net "FM_DIMM_EVENT_COD_N")
		)
		(pad "79" smd rect
			(at 0 71.399908 270)
			(size 1.8034 0.508)
			(layers "B.Cu" "B.Mask" "B.Paste")
			(net "M_C_MA<0>")
		)
		(pad "80" smd rect
			(at 0 72.250046 270)
			(size 1.8034 0.508)
			(layers "B.Cu" "B.Mask" "B.Paste")
			(net "PVDDQ_ABC")
		)
		(pad "81" smd rect
			(at 0 73.09993 270)
			(size 1.8034 0.508)
			(layers "B.Cu" "B.Mask" "B.Paste")
			(net "M_C_BA<0>")
		)
		(pad "82" smd rect
			(at 0 73.950068 270)
			(size 1.8034 0.508)
			(layers "B.Cu" "B.Mask" "B.Paste")
			(net "M_C_MA<16>")
		)
		(pad "83" smd rect
			(at 0 74.799952 270)
			(size 1.8034 0.508)
			(layers "B.Cu" "B.Mask" "B.Paste")
			(net "PVDDQ_ABC")
		)
		(pad "84" smd rect
			(at 0 75.65009 270)
			(size 1.8034 0.508)
			(layers "B.Cu" "B.Mask" "B.Paste")
			(net "M_C_CS_N<4>")
		)
		(pad "85" smd rect
			(at 0 76.499974 270)
			(size 1.8034 0.508)
			(layers "B.Cu" "B.Mask" "B.Paste")
			(net "PVDDQ_ABC")
		)
		(pad "86" smd rect
			(at 0 77.350112 270)
			(size 1.8034 0.508)
			(layers "B.Cu" "B.Mask" "B.Paste")
			(net "M_C_MA<15>")
		)
		(pad "87" smd rect
			(at 0 78.199996 270)
			(size 1.8034 0.508)
			(layers "B.Cu" "B.Mask" "B.Paste")
			(net "M_C_ODT<2>")
		)
		(pad "88" smd rect
			(at 0 79.04988 270)
			(size 1.8034 0.508)
			(layers "B.Cu" "B.Mask" "B.Paste")
			(net "PVDDQ_ABC")
		)
		(pad "89" smd rect
			(at 0 79.900018 270)
			(size 1.8034 0.508)
			(layers "B.Cu" "B.Mask" "B.Paste")
			(net "M_C_CS_N<5>")
		)
		(pad "90" smd rect
			(at 0 80.749902 270)
			(size 1.8034 0.508)
			(layers "B.Cu" "B.Mask" "B.Paste")
			(net "PVDDQ_ABC")
		)
		(pad "91" smd rect
			(at 0 81.60004 270)
			(size 1.8034 0.508)
			(layers "B.Cu" "B.Mask" "B.Paste")
			(net "M_C_ODT<3>")
		)
		(pad "92" smd rect
			(at 0 82.449924 270)
			(size 1.8034 0.508)
			(layers "B.Cu" "B.Mask" "B.Paste")
			(net "PVDDQ_ABC")
		)
		(pad "93" smd rect
			(at 0 83.300062 270)
			(size 1.8034 0.508)
			(layers "B.Cu" "B.Mask" "B.Paste")
			(net "M_C_CS_N<6>")
		)
		(pad "94" smd rect
			(at 0 84.149946 270)
			(size 1.8034 0.508)
			(layers "B.Cu" "B.Mask" "B.Paste")
			(net "GND")
		)
		(pad "95" smd rect
			(at 0 85.000084 270)
			(size 1.8034 0.508)
			(layers "B.Cu" "B.Mask" "B.Paste")
			(net "M_C_DQ<36>")
		)
		(pad "96" smd rect
			(at 0 85.849968 270)
			(size 1.8034 0.508)
			(layers "B.Cu" "B.Mask" "B.Paste")
			(net "GND")
		)
		(pad "97" smd rect
			(at 0 86.700106 270)
			(size 1.8034 0.508)
			(layers "B.Cu" "B.Mask" "B.Paste")
			(net "M_C_DQ<32>")
		)
		(pad "98" smd rect
			(at 0 87.54999 270)
			(size 1.8034 0.508)
			(layers "B.Cu" "B.Mask" "B.Paste")
			(net "GND")
		)
		(pad "99" smd rect
			(at 0 88.399874 270)
			(size 1.8034 0.508)
			(layers "B.Cu" "B.Mask" "B.Paste")
			(net "M_C_DQS_DP<13>")
		)
		(pad "100" smd rect
			(at 0 89.250012 270)
			(size 1.8034 0.508)
			(layers "B.Cu" "B.Mask" "B.Paste")
			(net "M_C_DQS_DN<13>")
		)
		(pad "101" smd rect
			(at 0 90.099896 270)
			(size 1.8034 0.508)
			(layers "B.Cu" "B.Mask" "B.Paste")
			(net "GND")
		)
		(pad "102" smd rect
			(at 0 90.950034 270)
			(size 1.8034 0.508)
			(layers "B.Cu" "B.Mask" "B.Paste")
			(net "M_C_DQ<38>")
		)
		(pad "103" smd rect
			(at 0 91.799918 270)
			(size 1.8034 0.508)
			(layers "B.Cu" "B.Mask" "B.Paste")
			(net "GND")
		)
		(pad "104" smd rect
			(at 0 92.650056 270)
			(size 1.8034 0.508)
			(layers "B.Cu" "B.Mask" "B.Paste")
			(net "M_C_DQ<34>")
		)
		(pad "105" smd rect
			(at 0 93.49994 270)
			(size 1.8034 0.508)
			(layers "B.Cu" "B.Mask" "B.Paste")
			(net "GND")
		)
		(pad "106" smd rect
			(at 0 94.350078 270)
			(size 1.8034 0.508)
			(layers "B.Cu" "B.Mask" "B.Paste")
			(net "M_C_DQ<44>")
		)
		(pad "107" smd rect
			(at 0 95.199962 270)
			(size 1.8034 0.508)
			(layers "B.Cu" "B.Mask" "B.Paste")
			(net "GND")
		)
		(pad "108" smd rect
			(at 0 96.0501 270)
			(size 1.8034 0.508)
			(layers "B.Cu" "B.Mask" "B.Paste")
			(net "M_C_DQ<40>")
		)
		(pad "109" smd rect
			(at 0 96.899984 270)
			(size 1.8034 0.508)
			(layers "B.Cu" "B.Mask" "B.Paste")
			(net "GND")
		)
		(pad "110" smd rect
			(at 0 97.750122 270)
			(size 1.8034 0.508)
			(layers "B.Cu" "B.Mask" "B.Paste")
			(net "M_C_DQS_DP<14>")
		)
		(pad "111" smd rect
			(at 0 98.600006 270)
			(size 1.8034 0.508)
			(layers "B.Cu" "B.Mask" "B.Paste")
			(net "M_C_DQS_DN<14>")
		)
		(pad "112" smd rect
			(at 0 99.44989 270)
			(size 1.8034 0.508)
			(layers "B.Cu" "B.Mask" "B.Paste")
			(net "GND")
		)
		(pad "113" smd rect
			(at 0 100.300028 270)
			(size 1.8034 0.508)
			(layers "B.Cu" "B.Mask" "B.Paste")
			(net "M_C_DQ<46>")
		)
		(pad "114" smd rect
			(at 0 101.149912 270)
			(size 1.8034 0.508)
			(layers "B.Cu" "B.Mask" "B.Paste")
			(net "GND")
		)
		(pad "115" smd rect
			(at 0 102.00005 270)
			(size 1.8034 0.508)
			(layers "B.Cu" "B.Mask" "B.Paste")
			(net "M_C_DQ<42>")
		)
		(pad "116" smd rect
			(at 0 102.849934 270)
			(size 1.8034 0.508)
			(layers "B.Cu" "B.Mask" "B.Paste")
			(net "GND")
		)
		(pad "117" smd rect
			(at 0 103.700072 270)
			(size 1.8034 0.508)
			(layers "B.Cu" "B.Mask" "B.Paste")
			(net "M_C_DQ<52>")
		)
		(pad "118" smd rect
			(at 0 104.549956 270)
			(size 1.8034 0.508)
			(layers "B.Cu" "B.Mask" "B.Paste")
			(net "GND")
		)
		(pad "119" smd rect
			(at 0 105.400094 270)
			(size 1.8034 0.508)
			(layers "B.Cu" "B.Mask" "B.Paste")
			(net "M_C_DQ<48>")
		)
		(pad "120" smd rect
			(at 0 106.249978 270)
			(size 1.8034 0.508)
			(layers "B.Cu" "B.Mask" "B.Paste")
			(net "GND")
		)
	)
)
